(kicad_pcb
	(version 20260206)
	(generator "pcbnew")
	(generator_version "10.0")
	(general
		(thickness 1.6)
		(legacy_teardrops no)
	)
	(paper "A4")
	(title_block
		(title "03242023_DA0F0TMBIJ0_F0T_Motherboard_J_brd_V01_OCP.brd")
		(comment 1 "Grand Teton / footprints 3367-3371 of 6105")
	)
	(layers
		(0 "F.Cu" signal "TOP")
		(4 "In1.Cu" signal "GND")
		(6 "In2.Cu" signal "IN1")
		(8 "In3.Cu" signal "GND1")
		(10 "In4.Cu" signal "IN2")
		(12 "In5.Cu" signal "GND2")
		(14 "In6.Cu" signal "IN3")
		(16 "In7.Cu" signal "GND3")
		(18 "In8.Cu" signal "VCC")
		(20 "In9.Cu" signal "VCC1")
		(22 "In10.Cu" signal "GND4")
		(24 "In11.Cu" signal "IN4")
		(26 "In12.Cu" signal "GND5")
		(28 "In13.Cu" signal "IN5")
		(30 "In14.Cu" signal "GND6")
		(32 "In15.Cu" signal "IN6")
		(34 "In16.Cu" signal "GND7")
		(2 "B.Cu" signal "BOTTOM")
		(9 "F.Adhes" user "F.Adhesive")
		(11 "B.Adhes" user "B.Adhesive")
		(13 "F.Paste" user "Package Geometry/Pastemask Top")
		(15 "B.Paste" user "Package Geometry/Pastemask Bottom")
		(5 "F.SilkS" user "Ref Des/Silkscreen Top")
		(7 "B.SilkS" user "Ref Des/Silkscreen Bottom")
		(1 "F.Mask" user "Board Geometry/Soldermask Top")
		(3 "B.Mask" user "Board Geometry/Soldermask Bottom")
		(17 "Dwgs.User" user "User.Drawings")
		(19 "Cmts.User" user "User.Comments")
		(21 "Eco1.User" user "User.Eco1")
		(23 "Eco2.User" user "User.Eco2")
		(25 "Edge.Cuts" user "Board Geometry/Outline")
		(27 "Margin" user)
		(31 "F.CrtYd" user "Package Geometry/Place Bound Top")
		(29 "B.CrtYd" user "Package Geometry/Place Bound Bottom")
		(35 "F.Fab" user "Ref Des/Assembly Top")
		(33 "B.Fab" user "Ref Des/Assembly Bottom")
	)
	(footprint ""
		(layer "F.Cu")
		(at 256.889504 -42.488612 180)
		(property "Reference" "PR3966"
			(at 0 0 180)
			(layer "F.SilkS")
			(hide yes)
			(effects
				(font
					(size 1.27 1.27)
				)
			)
		)
		(property "Value" ""
			(at 0 0 180)
			(layer "F.Fab")
			(effects
				(font
					(size 1.27 1.27)
				)
			)
		)
		(duplicate_pad_numbers_are_jumpers no)
		(fp_line
			(start 0.7874 0.4064)
			(end -0.7874 0.4064)
			(stroke
				(width 0.1524)
				(type default)
			)
			(layer "F.SilkS")
		)
		(fp_line
			(start 0.7874 -0.4064)
			(end 0.7874 0.4064)
			(stroke
				(width 0.1524)
				(type default)
			)
			(layer "F.SilkS")
		)
		(fp_line
			(start -0.7874 0.4064)
			(end -0.7874 -0.4064)
			(stroke
				(width 0.1524)
				(type default)
			)
			(layer "F.SilkS")
		)
		(fp_line
			(start -0.7874 -0.4064)
			(end 0.7874 -0.4064)
			(stroke
				(width 0.1524)
				(type default)
			)
			(layer "F.SilkS")
		)
		(fp_line
			(start 0.67945 0.3048)
			(end 0.120396 0.3048)
			(stroke
				(width 0.1)
				(type default)
			)
			(layer "F.Fab")
		)
		(fp_line
			(start 0.67945 -0.3048)
			(end 0.67945 0.3048)
			(stroke
				(width 0.1)
				(type default)
			)
			(layer "F.Fab")
		)
		(fp_line
			(start 0.12065 -0.2794)
			(end 0.12065 -0.3048)
			(stroke
				(width 0.1)
				(type default)
			)
			(layer "F.Fab")
		)
		(fp_line
			(start 0.12065 -0.3048)
			(end 0.67945 -0.3048)
			(stroke
				(width 0.1)
				(type default)
			)
			(layer "F.Fab")
		)
		(fp_line
			(start 0.120396 0.3048)
			(end 0.120396 0.2794)
			(stroke
				(width 0.1)
				(type default)
			)
			(layer "F.Fab")
		)
		(fp_line
			(start 0.120396 0.2794)
			(end -0.12065 0.2794)
			(stroke
				(width 0.1)
				(type default)
			)
			(layer "F.Fab")
		)
		(fp_line
			(start -0.12065 0.3048)
			(end -0.67945 0.3048)
			(stroke
				(width 0.1)
				(type default)
			)
			(layer "F.Fab")
		)
		(fp_line
			(start -0.12065 0.2794)
			(end -0.12065 0.3048)
			(stroke
				(width 0.1)
				(type default)
			)
			(layer "F.Fab")
		)
		(fp_line
			(start -0.12065 -0.2794)
			(end 0.12065 -0.2794)
			(stroke
				(width 0.1)
				(type default)
			)
			(layer "F.Fab")
		)
		(fp_line
			(start -0.12065 -0.305054)
			(end -0.12065 -0.2794)
			(stroke
				(width 0.1)
				(type default)
			)
			(layer "F.Fab")
		)
		(fp_line
			(start -0.67945 0.3048)
			(end -0.67945 -0.305054)
			(stroke
				(width 0.1)
				(type default)
			)
			(layer "F.Fab")
		)
		(fp_line
			(start -0.67945 -0.305054)
			(end -0.12065 -0.305054)
			(stroke
				(width 0.1)
				(type default)
			)
			(layer "F.Fab")
		)
		(pad "1" smd circle
			(at -0.40005 0 180)
			(size 0 0)
			(layers "F.Cu" "F.Mask" "F.Paste")
			(net "P12V_AUX")
		)
		(pad "2" smd circle
			(at 0.40005 0 180)
			(size 0 0)
			(layers "F.Cu" "F.Mask" "F.Paste")
			(net "P12V_E1S_VCC_0")
		)
	)
	(footprint ""
		(layer "F.Cu")
		(at 180.77688 -56.352948 180)
		(property "Reference" "R478"
			(at 0 0 180)
			(layer "F.SilkS")
			(hide yes)
			(effects
				(font
					(size 1.27 1.27)
				)
			)
		)
		(property "Value" ""
			(at 0 0 180)
			(layer "F.Fab")
			(effects
				(font
					(size 1.27 1.27)
				)
			)
		)
		(duplicate_pad_numbers_are_jumpers no)
		(fp_line
			(start 0.7874 0.4064)
			(end -0.7874 0.4064)
			(stroke
				(width 0.1524)
				(type default)
			)
			(layer "F.SilkS")
		)
		(fp_line
			(start 0.7874 -0.4064)
			(end 0.7874 0.4064)
			(stroke
				(width 0.1524)
				(type default)
			)
			(layer "F.SilkS")
		)
		(fp_line
			(start -0.7874 0.4064)
			(end -0.7874 -0.4064)
			(stroke
				(width 0.1524)
				(type default)
			)
			(layer "F.SilkS")
		)
		(fp_line
			(start -0.7874 -0.4064)
			(end 0.7874 -0.4064)
			(stroke
				(width 0.1524)
				(type default)
			)
			(layer "F.SilkS")
		)
		(fp_line
			(start 0.67945 0.3048)
			(end 0.120396 0.3048)
			(stroke
				(width 0.1)
				(type default)
			)
			(layer "F.Fab")
		)
		(fp_line
			(start 0.67945 -0.3048)
			(end 0.67945 0.3048)
			(stroke
				(width 0.1)
				(type default)
			)
			(layer "F.Fab")
		)
		(fp_line
			(start 0.12065 -0.2794)
			(end 0.12065 -0.3048)
			(stroke
				(width 0.1)
				(type default)
			)
			(layer "F.Fab")
		)
		(fp_line
			(start 0.12065 -0.3048)
			(end 0.67945 -0.3048)
			(stroke
				(width 0.1)
				(type default)
			)
			(layer "F.Fab")
		)
		(fp_line
			(start 0.120396 0.3048)
			(end 0.120396 0.2794)
			(stroke
				(width 0.1)
				(type default)
			)
			(layer "F.Fab")
		)
		(fp_line
			(start 0.120396 0.2794)
			(end -0.12065 0.2794)
			(stroke
				(width 0.1)
				(type default)
			)
			(layer "F.Fab")
		)
		(fp_line
			(start -0.12065 0.3048)
			(end -0.67945 0.3048)
			(stroke
				(width 0.1)
				(type default)
			)
			(layer "F.Fab")
		)
		(fp_line
			(start -0.12065 0.2794)
			(end -0.12065 0.3048)
			(stroke
				(width 0.1)
				(type default)
			)
			(layer "F.Fab")
		)
		(fp_line
			(start -0.12065 -0.2794)
			(end 0.12065 -0.2794)
			(stroke
				(width 0.1)
				(type default)
			)
			(layer "F.Fab")
		)
		(fp_line
			(start -0.12065 -0.305054)
			(end -0.12065 -0.2794)
			(stroke
				(width 0.1)
				(type default)
			)
			(layer "F.Fab")
		)
		(fp_line
			(start -0.67945 0.3048)
			(end -0.67945 -0.305054)
			(stroke
				(width 0.1)
				(type default)
			)
			(layer "F.Fab")
		)
		(fp_line
			(start -0.67945 -0.305054)
			(end -0.12065 -0.305054)
			(stroke
				(width 0.1)
				(type default)
			)
			(layer "F.Fab")
		)
		(pad "1" smd circle
			(at -0.40005 0 180)
			(size 0 0)
			(layers "F.Cu" "F.Mask" "F.Paste")
			(net "P3V3_AUX")
		)
		(pad "2" smd circle
			(at 0.40005 0 180)
			(size 0 0)
			(layers "F.Cu" "F.Mask" "F.Paste")
			(net "PCIE_M2_SSD0_PRSNT_N")
		)
	)
	(footprint ""
		(layer "F.Cu")
		(at 97.821242 -417.766246 90)
		(property "Reference" "R4194"
			(at 0 0 90)
			(layer "F.SilkS")
			(hide yes)
			(effects
				(font
					(size 1.27 1.27)
				)
			)
		)
		(property "Value" ""
			(at 0 0 90)
			(layer "F.Fab")
			(effects
				(font
					(size 1.27 1.27)
				)
			)
		)
		(duplicate_pad_numbers_are_jumpers no)
		(fp_line
			(start 0.7874 -0.4064)
			(end 0.7874 0.4064)
			(stroke
				(width 0.1524)
				(type default)
			)
			(layer "F.SilkS")
		)
		(fp_line
			(start -0.7874 -0.4064)
			(end 0.7874 -0.4064)
			(stroke
				(width 0.1524)
				(type default)
			)
			(layer "F.SilkS")
		)
		(fp_line
			(start 0.7874 0.4064)
			(end -0.7874 0.4064)
			(stroke
				(width 0.1524)
				(type default)
			)
			(layer "F.SilkS")
		)
		(fp_line
			(start -0.7874 0.4064)
			(end -0.7874 -0.4064)
			(stroke
				(width 0.1524)
				(type default)
			)
			(layer "F.SilkS")
		)
		(fp_line
			(start -0.12065 -0.305054)
			(end -0.12065 -0.2794)
			(stroke
				(width 0.1)
				(type default)
			)
			(layer "F.Fab")
		)
		(fp_line
			(start -0.67945 -0.305054)
			(end -0.12065 -0.305054)
			(stroke
				(width 0.1)
				(type default)
			)
			(layer "F.Fab")
		)
		(fp_line
			(start 0.67945 -0.3048)
			(end 0.67945 0.3048)
			(stroke
				(width 0.1)
				(type default)
			)
			(layer "F.Fab")
		)
		(fp_line
			(start 0.12065 -0.3048)
			(end 0.67945 -0.3048)
			(stroke
				(width 0.1)
				(type default)
			)
			(layer "F.Fab")
		)
		(fp_line
			(start 0.12065 -0.2794)
			(end 0.12065 -0.3048)
			(stroke
				(width 0.1)
				(type default)
			)
			(layer "F.Fab")
		)
		(fp_line
			(start -0.12065 -0.2794)
			(end 0.12065 -0.2794)
			(stroke
				(width 0.1)
				(type default)
			)
			(layer "F.Fab")
		)
		(fp_line
			(start 0.120396 0.2794)
			(end -0.12065 0.2794)
			(stroke
				(width 0.1)
				(type default)
			)
			(layer "F.Fab")
		)
		(fp_line
			(start -0.12065 0.2794)
			(end -0.12065 0.3048)
			(stroke
				(width 0.1)
				(type default)
			)
			(layer "F.Fab")
		)
		(fp_line
			(start 0.67945 0.3048)
			(end 0.120396 0.3048)
			(stroke
				(width 0.1)
				(type default)
			)
			(layer "F.Fab")
		)
		(fp_line
			(start 0.120396 0.3048)
			(end 0.120396 0.2794)
			(stroke
				(width 0.1)
				(type default)
			)
			(layer "F.Fab")
		)
		(fp_line
			(start -0.12065 0.3048)
			(end -0.67945 0.3048)
			(stroke
				(width 0.1)
				(type default)
			)
			(layer "F.Fab")
		)
		(fp_line
			(start -0.67945 0.3048)
			(end -0.67945 -0.305054)
			(stroke
				(width 0.1)
				(type default)
			)
			(layer "F.Fab")
		)
		(pad "1" smd circle
			(at -0.40005 0 90)
			(size 0 0)
			(layers "F.Cu" "F.Mask" "F.Paste")
			(net "P3V3_AUX")
		)
		(pad "2" smd circle
			(at 0.40005 0 90)
			(size 0 0)
			(layers "F.Cu" "F.Mask" "F.Paste")
			(net "U272_2_ADD1")
		)
	)
	(footprint ""
		(layer "F.Cu")
		(at 303.9872 -24.7396 180)
		(property "Reference" "C2386"
			(at 0 0 180)
			(layer "F.SilkS")
			(hide yes)
			(effects
				(font
					(size 1.27 1.27)
				)
			)
		)
		(property "Value" ""
			(at 0 0 180)
			(layer "F.Fab")
			(effects
				(font
					(size 1.27 1.27)
				)
			)
		)
		(duplicate_pad_numbers_are_jumpers no)
		(fp_line
			(start 0.7874 0.4064)
			(end -0.7874 0.4064)
			(stroke
				(width 0.1524)
				(type default)
			)
			(layer "F.SilkS")
		)
		(fp_line
			(start 0.7874 -0.4064)
			(end 0.7874 0.4064)
			(stroke
				(width 0.1524)
				(type default)
			)
			(layer "F.SilkS")
		)
		(fp_line
			(start -0.7874 0.4064)
			(end -0.7874 -0.4064)
			(stroke
				(width 0.1524)
				(type default)
			)
			(layer "F.SilkS")
		)
		(fp_line
			(start -0.7874 -0.4064)
			(end 0.7874 -0.4064)
			(stroke
				(width 0.1524)
				(type default)
			)
			(layer "F.SilkS")
		)
		(fp_line
			(start 0.67945 0.3048)
			(end 0.120396 0.3048)
			(stroke
				(width 0.1)
				(type default)
			)
			(layer "F.Fab")
		)
		(fp_line
			(start 0.67945 -0.3048)
			(end 0.67945 0.3048)
			(stroke
				(width 0.1)
				(type default)
			)
			(layer "F.Fab")
		)
		(fp_line
			(start 0.12065 -0.2794)
			(end 0.12065 -0.3048)
			(stroke
				(width 0.1)
				(type default)
			)
			(layer "F.Fab")
		)
		(fp_line
			(start 0.12065 -0.3048)
			(end 0.67945 -0.3048)
			(stroke
				(width 0.1)
				(type default)
			)
			(layer "F.Fab")
		)
		(fp_line
			(start 0.120396 0.3048)
			(end 0.120396 0.2794)
			(stroke
				(width 0.1)
				(type default)
			)
			(layer "F.Fab")
		)
		(fp_line
			(start 0.120396 0.2794)
			(end -0.12065 0.2794)
			(stroke
				(width 0.1)
				(type default)
			)
			(layer "F.Fab")
		)
		(fp_line
			(start -0.12065 0.3048)
			(end -0.67945 0.3048)
			(stroke
				(width 0.1)
				(type default)
			)
			(layer "F.Fab")
		)
		(fp_line
			(start -0.12065 0.2794)
			(end -0.12065 0.3048)
			(stroke
				(width 0.1)
				(type default)
			)
			(layer "F.Fab")
		)
		(fp_line
			(start -0.12065 -0.2794)
			(end 0.12065 -0.2794)
			(stroke
				(width 0.1)
				(type default)
			)
			(layer "F.Fab")
		)
		(fp_line
			(start -0.12065 -0.305054)
			(end -0.12065 -0.2794)
			(stroke
				(width 0.1)
				(type default)
			)
			(layer "F.Fab")
		)
		(fp_line
			(start -0.67945 0.3048)
			(end -0.67945 -0.305054)
			(stroke
				(width 0.1)
				(type default)
			)
			(layer "F.Fab")
		)
		(fp_line
			(start -0.67945 -0.305054)
			(end -0.12065 -0.305054)
			(stroke
				(width 0.1)
				(type default)
			)
			(layer "F.Fab")
		)
		(pad "1" smd circle
			(at -0.40005 0 180)
			(size 0 0)
			(layers "F.Cu" "F.Mask" "F.Paste")
			(net "PWRGD_DSW_PWROK_TRIGGER")
		)
		(pad "2" smd circle
			(at 0.40005 0 180)
			(size 0 0)
			(layers "F.Cu" "F.Mask" "F.Paste")
			(net "GND")
		)
	)
	(footprint ""
		(layer "F.Cu")
		(at 509.384808 -148.08708 90)
		(property "Reference" "X14"
			(at -3.417316 3.094482 90)
			(unlocked yes)
			(layer "F.SilkS")
			(effects
				(font
					(size 0.7874 0.5842)
					(thickness 0.1524)
				)
				(justify left)
			)
		)
		(property "Value" ""
			(at 0 0 90)
			(layer "F.Fab")
			(effects
				(font
					(size 1.27 1.27)
				)
			)
		)
		(property "Device Type" "TP_TDR_4P_FTS_MPKT4_H025P0200_I"
			(at 1.30175 1.27 180)
			(unlocked yes)
			(layer "F.Fab")
			(hide yes)
			(effects
				(font
					(size 0.635 0.4064)
					(thickness 0.1524)
				)
			)
		)
		(property "User Part Number" "TP15"
			(at 1.30175 1.27 180)
			(unlocked yes)
			(layer "Cmts.User")
			(hide yes)
			(effects
				(font
					(size 0.635 0.4064)
					(thickness 0.1524)
				)
			)
		)
		(duplicate_pad_numbers_are_jumpers no)
		(fp_line
			(start 2.54 -1.27)
			(end 0 -1.27)
			(stroke
				(width 0.1524)
				(type default)
			)
			(layer "F.SilkS")
		)
		(fp_line
			(start 0 -1.27)
			(end 0 -0.635)
			(stroke
				(width 0.1524)
				(type default)
			)
			(layer "F.SilkS")
		)
		(fp_line
			(start 2.54 -1.1303)
			(end 2.54 -1.27)
			(stroke
				(width 0.1524)
				(type default)
			)
			(layer "F.SilkS")
		)
		(fp_line
			(start 0 0.635)
			(end 0 1.905)
			(stroke
				(width 0.1524)
				(type default)
			)
			(layer "F.SilkS")
		)
		(fp_line
			(start 2.54 1.4097)
			(end 2.54 1.1303)
			(stroke
				(width 0.1524)
				(type default)
			)
			(layer "F.SilkS")
		)
		(fp_line
			(start 0 3.175)
			(end 0 3.81)
			(stroke
				(width 0.1524)
				(type default)
			)
			(layer "F.SilkS")
		)
		(fp_line
			(start 2.54 3.81)
			(end 2.54 3.6703)
			(stroke
				(width 0.1524)
				(type default)
			)
			(layer "F.SilkS")
		)
		(fp_line
			(start 0 3.81)
			(end 2.54 3.81)
			(stroke
				(width 0.1524)
				(type default)
			)
			(layer "F.SilkS")
		)
		(fp_poly
			(pts
				(xy -1.267206 -0.04064) (xy -2.791206 0.72136) (xy -2.791206 -0.80264)
			)
			(stroke
				(width 0)
				(type default)
			)
			(fill yes)
			(layer "F.SilkS")
		)
		(fp_line
			(start 2.54 -1.27)
			(end 0 -1.27)
			(stroke
				(width 0.1)
				(type default)
			)
			(layer "F.Fab")
		)
		(fp_line
			(start 0 -1.27)
			(end 0 3.81)
			(stroke
				(width 0.1)
				(type default)
			)
			(layer "F.Fab")
		)
		(fp_line
			(start 2.54 3.81)
			(end 2.54 -1.27)
			(stroke
				(width 0.1)
				(type default)
			)
			(layer "F.Fab")
		)
		(fp_line
			(start 0 3.81)
			(end 2.54 3.81)
			(stroke
				(width 0.1)
				(type default)
			)
			(layer "F.Fab")
		)
		(fp_poly
			(pts
				(xy -0.761746 0) (xy -2.285746 -0.762) (xy -2.285746 0.762)
			)
			(stroke
				(width 0)
				(type default)
			)
			(fill yes)
			(layer "F.Fab")
		)
		(pad "1" thru_hole circle
			(at 0 0 90)
			(size 1.0033 1.0033)
			(drill 0.249936)
			(layers "*.Cu" "*.Mask")
			(remove_unused_layers no)
			(net "TDR_DIFF_100_IN1_DP")
			(clearance 0.10795)
			(thermal_gap 0.10795)
			(padstack
				(mode front_inner_back)
				(layer "Inner"
					(shape circle)
					(size 0.8001 0.8001)
					(clearance 0.1524)
				)
				(layer "B.Cu"
					(shape circle)
					(size 1.0033 1.0033)
					(clearance 0.10795)
				)
			)
		)
		(pad "2" thru_hole circle
			(at 2.54 0 90)
			(size 1.9939 1.9939)
			(drill 0.249936)
			(layers "*.Cu" "*.Mask")
			(remove_unused_layers no)
			(net "T1_GND")
			(clearance 0.10795)
			(thermal_gap 0.10795)
			(padstack
				(mode front_inner_back)
				(layer "Inner"
					(shape circle)
					(size 0.8001 0.8001)
					(clearance 0.1524)
				)
				(layer "B.Cu"
					(shape circle)
					(size 1.9939 1.9939)
					(clearance 0.10795)
				)
			)
		)
		(pad "3" thru_hole circle
			(at 2.54 2.54 90)
			(size 1.9939 1.9939)
			(drill 0.249936)
			(layers "*.Cu" "*.Mask")
			(remove_unused_layers no)
			(net "T1_GND")
			(clearance 0.10795)
			(thermal_gap 0.10795)
			(padstack
				(mode front_inner_back)
				(layer "Inner"
					(shape circle)
					(size 0.8001 0.8001)
					(clearance 0.1524)
				)
				(layer "B.Cu"
					(shape circle)
					(size 1.9939 1.9939)
					(clearance 0.10795)
				)
			)
		)
		(pad "4" thru_hole circle
			(at 0 2.54 90)
			(size 1.0033 1.0033)
			(drill 0.249936)
			(layers "*.Cu" "*.Mask")
			(remove_unused_layers no)
			(net "TDR_DIFF_100_IN1_DN")
			(clearance 0.10795)
			(thermal_gap 0.10795)
			(padstack
				(mode front_inner_back)
				(layer "Inner"
					(shape circle)
					(size 0.8001 0.8001)
					(clearance 0.1524)
				)
				(layer "B.Cu"
					(shape circle)
					(size 1.0033 1.0033)
					(clearance 0.10795)
				)
			)
		)
	)
)
